(kicad_pcb
	(version 20241229)
	(generator "pcbnew")
	(generator_version "9.0")
	(general
		(thickness 1.711)
		(legacy_teardrops no)
	)
	(paper "A4")
	(title_block
		(title "Antmicro Baseboard for Jetson AGX Thor")
		(date "2026-02-18")
		(rev "1.1.0")
		(company "Antmicro Ltd")
		(comment 1 "www.antmicro.com")
		(comment 9 "footprints 580-584 of 1170")
	)
	(layers
		(0 "F.Cu" signal)
		(4 "In1.Cu" signal)
		(6 "In2.Cu" signal)
		(8 "In3.Cu" signal)
		(10 "In4.Cu" jumper)
		(12 "In5.Cu" signal)
		(14 "In6.Cu" signal)
		(16 "In7.Cu" signal)
		(18 "In8.Cu" signal)
		(2 "B.Cu" signal)
		(9 "F.Adhes" user "F.Adhesive")
		(11 "B.Adhes" user "B.Adhesive")
		(13 "F.Paste" user)
		(15 "B.Paste" user)
		(5 "F.SilkS" user "F.Silkscreen")
		(7 "B.SilkS" user "B.Silkscreen")
		(1 "F.Mask" user)
		(3 "B.Mask" user)
		(17 "Dwgs.User" user "User.Drawings")
		(19 "Cmts.User" user "User.Comments")
		(21 "Eco1.User" user "User.Eco1")
		(23 "Eco2.User" user "User.Eco2")
		(25 "Edge.Cuts" user)
		(27 "Margin" user)
		(31 "F.CrtYd" user "F.Courtyard")
		(29 "B.CrtYd" user "B.Courtyard")
		(35 "F.Fab" user)
		(33 "B.Fab" user)
	)
	(footprint "antmicro-footprints:R_0402_1005Metric"
		(layer "F.Cu")
		(at 138.2 104.8 -90)
		(descr "Resistor SMD 0402")
		(tags "resistor SMD 0402")
		(property "Reference" "R345"
			(at -3.8 0.3 90)
			(layer "F.SilkS")
			(effects
				(font
					(size 0.7 0.7)
					(thickness 0.15)
				)
				(justify right top)
			)
		)
		(property "Value" "R_0R_0402"
			(at -1.011843 1.772047 90)
			(layer "F.Fab")
			(effects
				(font
					(size 0.7 0.7)
					(thickness 0.15)
				)
				(justify right top)
			)
		)
		(property "Datasheet" "https://industrial.panasonic.com/cdbs/www-data/pdf/RDA0000/AOA0000C301.pdf"
			(at 0 0 90)
			(layer "F.Fab")
			(hide yes)
			(effects
				(font
					(size 1.27 1.27)
					(thickness 0.15)
				)
			)
		)
		(property "Description" "SMD Chip Resistor, Jumper, 0 ohm, 100 mW, 0402 [1005 Metric], Thick Film, General Purpose"
			(at 0 0 90)
			(layer "F.Fab")
			(hide yes)
			(effects
				(font
					(size 1.27 1.27)
					(thickness 0.15)
				)
			)
		)
		(property "Manufacturer" "Panasonic"
			(at 0 0 270)
			(unlocked yes)
			(layer "F.Fab")
			(hide yes)
			(effects
				(font
					(size 1 1)
					(thickness 0.15)
				)
			)
		)
		(property "MPN" "ERJ2GE0R00X"
			(at 0 0 270)
			(unlocked yes)
			(layer "F.Fab")
			(hide yes)
			(effects
				(font
					(size 1 1)
					(thickness 0.15)
				)
			)
		)
		(property "Val" "0R"
			(at 0 0 270)
			(unlocked yes)
			(layer "F.Fab")
			(hide yes)
			(effects
				(font
					(size 1 1)
					(thickness 0.15)
				)
			)
		)
		(property "License" "Apache-2.0"
			(at 0 0 270)
			(unlocked yes)
			(layer "F.Fab")
			(hide yes)
			(effects
				(font
					(size 1 1)
					(thickness 0.15)
				)
			)
		)
		(property "Author" "Antmicro"
			(at 0 0 270)
			(unlocked yes)
			(layer "F.Fab")
			(hide yes)
			(effects
				(font
					(size 1 1)
					(thickness 0.15)
				)
			)
		)
		(property "Tolerance" "~"
			(at 0 0 270)
			(unlocked yes)
			(layer "F.Fab")
			(hide yes)
			(effects
				(font
					(size 1 1)
					(thickness 0.15)
				)
			)
		)
		(property "Current" "1A"
			(at 0 0 270)
			(unlocked yes)
			(layer "F.Fab")
			(hide yes)
			(effects
				(font
					(size 1 1)
					(thickness 0.15)
				)
			)
		)
		(sheetname "/Peripherals/")
		(sheetfile "peripherals.kicad_sch")
		(attr smd)
		(fp_rect
			(start -0.925 -0.47)
			(end 0.925 0.47)
			(stroke
				(width 0.05)
				(type default)
			)
			(fill no)
			(layer "F.CrtYd")
		)
		(fp_rect
			(start -0.5 -0.25)
			(end 0.5 0.25)
			(stroke
				(width 0.15)
				(type solid)
			)
			(fill no)
			(layer "F.Fab")
		)
		(fp_text user "License: Apache-2.0"
			(at -0.95 5.169 90)
			(layer "F.Fab")
			(effects
				(font
					(size 0.7 0.7)
					(thickness 0.15)
				)
				(justify right top)
			)
		)
		(fp_text user "${REFERENCE}"
			(at -0.95 3.168 90)
			(layer "F.Fab")
			(effects
				(font
					(size 0.7 0.7)
					(thickness 0.15)
				)
				(justify right top)
			)
		)
		(fp_text user "Author: Antmicro"
			(at -0.95 4.169 90)
			(layer "F.Fab")
			(effects
				(font
					(size 0.7 0.7)
					(thickness 0.15)
				)
				(justify right top)
			)
		)
		(pad "1" smd roundrect
			(at -0.48 0 270)
			(size 0.59 0.64)
			(layers "F.Cu" "F.Mask" "F.Paste")
			(roundrect_rratio 0.25)
			(net 1 "GND")
			(pintype "passive")
		)
		(pad "2" smd roundrect
			(at 0.48 0 270)
			(size 0.59 0.64)
			(layers "F.Cu" "F.Mask" "F.Paste")
			(roundrect_rratio 0.25)
			(net 1311 "Net-(U71-ADDR)")
			(pintype "passive")
		)
	)
	(footprint "antmicro-footprints:C_0402_1005Metric"
		(layer "F.Cu")
		(at 218.7 126.7 180)
		(descr "Capacitor SMD 0402")
		(tags "capacitor SMD 0402")
		(property "Reference" "C82"
			(at 0.835 0.365 0)
			(layer "F.SilkS")
			(effects
				(font
					(size 0.7 0.7)
					(thickness 0.15)
				)
				(justify right top)
			)
		)
		(property "Value" "C_100n_0402"
			(at -1.022927 2.155213 0)
			(layer "F.Fab")
			(effects
				(font
					(size 0.7 0.7)
					(thickness 0.15)
				)
				(justify right top)
			)
		)
		(property "Datasheet" "https://www.murata.com/products/productdetail?partno=GRM155R61H104KE14%23"
			(at 0 0 0)
			(layer "F.Fab")
			(hide yes)
			(effects
				(font
					(size 1.27 1.27)
					(thickness 0.15)
				)
			)
		)
		(property "Description" "SMD Multilayer Ceramic Capacitor, 0.1 µF, 50 V, 0402 [1005 Metric], ± 10%, X5R, GRM Series"
			(at 0 0 0)
			(layer "F.Fab")
			(hide yes)
			(effects
				(font
					(size 1.27 1.27)
					(thickness 0.15)
				)
			)
		)
		(property "Manufacturer" "Murata"
			(at 0 0 180)
			(unlocked yes)
			(layer "F.Fab")
			(hide yes)
			(effects
				(font
					(size 1 1)
					(thickness 0.15)
				)
			)
		)
		(property "MPN" "GRM155R61H104KE14D"
			(at 0 0 180)
			(unlocked yes)
			(layer "F.Fab")
			(hide yes)
			(effects
				(font
					(size 1 1)
					(thickness 0.15)
				)
			)
		)
		(property "Val" "100n"
			(at 0 0 180)
			(unlocked yes)
			(layer "F.Fab")
			(hide yes)
			(effects
				(font
					(size 1 1)
					(thickness 0.15)
				)
			)
		)
		(property "License" "Apache-2.0"
			(at 0 0 180)
			(unlocked yes)
			(layer "F.Fab")
			(hide yes)
			(effects
				(font
					(size 1 1)
					(thickness 0.15)
				)
			)
		)
		(property "Author" "Antmicro"
			(at 0 0 180)
			(unlocked yes)
			(layer "F.Fab")
			(hide yes)
			(effects
				(font
					(size 1 1)
					(thickness 0.15)
				)
			)
		)
		(property "Voltage" "50V"
			(at 0 0 180)
			(unlocked yes)
			(layer "F.Fab")
			(hide yes)
			(effects
				(font
					(size 1 1)
					(thickness 0.15)
				)
			)
		)
		(property "Dielectric" "X5R"
			(at 0 0 180)
			(unlocked yes)
			(layer "F.Fab")
			(hide yes)
			(effects
				(font
					(size 1 1)
					(thickness 0.15)
				)
			)
		)
		(sheetname "/USB Hub/")
		(sheetfile "usb_hub.kicad_sch")
		(attr smd)
		(fp_rect
			(start -0.925 -0.47)
			(end 0.925 0.47)
			(stroke
				(width 0.05)
				(type default)
			)
			(fill no)
			(layer "F.CrtYd")
		)
		(fp_line
			(start 0.504 0.248)
			(end -0.494 0.248)
			(stroke
				(width 0.15)
				(type solid)
			)
			(layer "F.Fab")
		)
		(fp_line
			(start 0.504 -0.25)
			(end 0.504 0.248)
			(stroke
				(width 0.15)
				(type solid)
			)
			(layer "F.Fab")
		)
		(fp_line
			(start -0.494 0.248)
			(end -0.494 -0.25)
			(stroke
				(width 0.15)
				(type solid)
			)
			(layer "F.Fab")
		)
		(fp_line
			(start -0.494 -0.25)
			(end 0.504 -0.25)
			(stroke
				(width 0.15)
				(type solid)
			)
			(layer "F.Fab")
		)
		(fp_text user "${REFERENCE}"
			(at -0.939 4.599 0)
			(layer "F.Fab")
			(effects
				(font
					(size 0.7 0.7)
					(thickness 0.15)
				)
				(justify right top)
			)
		)
		(fp_text user "Author: Antmicro"
			(at -0.939 3.399 0)
			(layer "F.Fab")
			(effects
				(font
					(size 0.7 0.7)
					(thickness 0.15)
				)
				(justify right top)
			)
		)
		(fp_text user "License: Apache-2.0"
			(at -0.939 5.799 0)
			(layer "F.Fab")
			(effects
				(font
					(size 0.7 0.7)
					(thickness 0.15)
				)
				(justify right top)
			)
		)
		(pad "1" smd roundrect
			(at -0.48 0 180)
			(size 0.59 0.64)
			(layers "F.Cu" "F.Mask" "F.Paste")
			(roundrect_rratio 0.25)
			(net 80 "/USB Hub/USBC4_CONN_TX2_P")
			(pintype "passive")
		)
		(pad "2" smd roundrect
			(at 0.48 0 180)
			(size 0.59 0.64)
			(layers "F.Cu" "F.Mask" "F.Paste")
			(roundrect_rratio 0.25)
			(net 41 "/USB Hub/USBC4_TX_{2}+")
			(pintype "passive")
		)
	)
	(footprint "antmicro-footprints:C_0402_1005Metric"
		(layer "F.Cu")
		(at 152.48 109.5)
		(descr "Capacitor SMD 0402")
		(tags "capacitor SMD 0402")
		(property "Reference" "C10"
			(at 1.12 0.4 0)
			(layer "F.SilkS")
			(effects
				(font
					(size 0.7 0.7)
					(thickness 0.15)
				)
				(justify left bottom)
			)
		)
		(property "Value" "C_100n_0402"
			(at -1.022927 2.155213 0)
			(layer "F.Fab")
			(effects
				(font
					(size 0.7 0.7)
					(thickness 0.15)
				)
				(justify left bottom)
			)
		)
		(property "Datasheet" "https://www.murata.com/products/productdetail?partno=GRM155R61H104KE14%23"
			(at 0 0 0)
			(layer "F.Fab")
			(hide yes)
			(effects
				(font
					(size 1.27 1.27)
					(thickness 0.15)
				)
			)
		)
		(property "Description" "SMD Multilayer Ceramic Capacitor, 0.1 µF, 50 V, 0402 [1005 Metric], ± 10%, X5R, GRM Series"
			(at 0 0 0)
			(layer "F.Fab")
			(hide yes)
			(effects
				(font
					(size 1.27 1.27)
					(thickness 0.15)
				)
			)
		)
		(property "Manufacturer" "Murata"
			(at 0 0 0)
			(unlocked yes)
			(layer "F.Fab")
			(hide yes)
			(effects
				(font
					(size 1 1)
					(thickness 0.15)
				)
			)
		)
		(property "MPN" "GRM155R61H104KE14D"
			(at 0 0 0)
			(unlocked yes)
			(layer "F.Fab")
			(hide yes)
			(effects
				(font
					(size 1 1)
					(thickness 0.15)
				)
			)
		)
		(property "Val" "100n"
			(at 0 0 0)
			(unlocked yes)
			(layer "F.Fab")
			(hide yes)
			(effects
				(font
					(size 1 1)
					(thickness 0.15)
				)
			)
		)
		(property "License" "Apache-2.0"
			(at 0 0 0)
			(unlocked yes)
			(layer "F.Fab")
			(hide yes)
			(effects
				(font
					(size 1 1)
					(thickness 0.15)
				)
			)
		)
		(property "Author" "Antmicro"
			(at 0 0 0)
			(unlocked yes)
			(layer "F.Fab")
			(hide yes)
			(effects
				(font
					(size 1 1)
					(thickness 0.15)
				)
			)
		)
		(property "Voltage" "50V"
			(at 0 0 0)
			(unlocked yes)
			(layer "F.Fab")
			(hide yes)
			(effects
				(font
					(size 1 1)
					(thickness 0.15)
				)
			)
		)
		(property "Dielectric" "X5R"
			(at 0 0 0)
			(unlocked yes)
			(layer "F.Fab")
			(hide yes)
			(effects
				(font
					(size 1 1)
					(thickness 0.15)
				)
			)
		)
		(sheetname "/SoM_IO/")
		(sheetfile "som_io.kicad_sch")
		(attr smd)
		(fp_poly
			(pts
				(xy -0.925 -0.47) (xy -0.925 0.47) (xy 0.925 0.47) (xy 0.925 -0.47)
			)
			(stroke
				(width 0.05)
				(type default)
			)
			(fill no)
			(layer "F.CrtYd")
		)
		(fp_line
			(start -0.494 -0.25)
			(end 0.504 -0.25)
			(stroke
				(width 0.15)
				(type solid)
			)
			(layer "F.Fab")
		)
		(fp_line
			(start -0.494 0.248)
			(end -0.494 -0.25)
			(stroke
				(width 0.15)
				(type solid)
			)
			(layer "F.Fab")
		)
		(fp_line
			(start 0.504 -0.25)
			(end 0.504 0.248)
			(stroke
				(width 0.15)
				(type solid)
			)
			(layer "F.Fab")
		)
		(fp_line
			(start 0.504 0.248)
			(end -0.494 0.248)
			(stroke
				(width 0.15)
				(type solid)
			)
			(layer "F.Fab")
		)
		(fp_text user "License: Apache-2.0"
			(at -0.939 5.799 0)
			(layer "F.Fab")
			(effects
				(font
					(size 0.7 0.7)
					(thickness 0.15)
				)
				(justify left bottom)
			)
		)
		(fp_text user "Author: Antmicro"
			(at -0.939 3.399 0)
			(layer "F.Fab")
			(effects
				(font
					(size 0.7 0.7)
					(thickness 0.15)
				)
				(justify left bottom)
			)
		)
		(fp_text user "${REFERENCE}"
			(at -0.939 4.599 0)
			(layer "F.Fab")
			(effects
				(font
					(size 0.7 0.7)
					(thickness 0.15)
				)
				(justify left bottom)
			)
		)
		(pad "1" smd roundrect
			(at -0.48 0)
			(size 0.59 0.64)
			(layers "F.Cu" "F.Mask" "F.Paste")
			(roundrect_rratio 0.25)
			(net 1 "GND")
			(pintype "passive")
		)
		(pad "2" smd roundrect
			(at 0.48 0)
			(size 0.59 0.64)
			(layers "F.Cu" "F.Mask" "F.Paste")
			(roundrect_rratio 0.25)
			(net 2 "+3V3")
			(pintype "passive")
		)
	)
	(footprint "antmicro-footprints:C_0402_1005Metric"
		(layer "F.Cu")
		(at 151.5 107.5)
		(descr "Capacitor SMD 0402")
		(tags "capacitor SMD 0402")
		(property "Reference" "C356"
			(at -3.8 0.3 0)
			(layer "F.SilkS")
			(effects
				(font
					(size 0.7 0.7)
					(thickness 0.15)
				)
				(justify left bottom)
			)
		)
		(property "Value" "C_100n_0402"
			(at -1.022927 2.155213 0)
			(layer "F.Fab")
			(effects
				(font
					(size 0.7 0.7)
					(thickness 0.15)
				)
				(justify left bottom)
			)
		)
		(property "Datasheet" "https://www.murata.com/products/productdetail?partno=GRM155R61H104KE14%23"
			(at 0 0 0)
			(layer "F.Fab")
			(hide yes)
			(effects
				(font
					(size 1.27 1.27)
					(thickness 0.15)
				)
			)
		)
		(property "Description" "SMD Multilayer Ceramic Capacitor, 0.1 µF, 50 V, 0402 [1005 Metric], ± 10%, X5R, GRM Series"
			(at 0 0 0)
			(layer "F.Fab")
			(hide yes)
			(effects
				(font
					(size 1.27 1.27)
					(thickness 0.15)
				)
			)
		)
		(property "Manufacturer" "Murata"
			(at 0 0 0)
			(unlocked yes)
			(layer "F.Fab")
			(hide yes)
			(effects
				(font
					(size 1 1)
					(thickness 0.15)
				)
			)
		)
		(property "MPN" "GRM155R61H104KE14D"
			(at 0 0 0)
			(unlocked yes)
			(layer "F.Fab")
			(hide yes)
			(effects
				(font
					(size 1 1)
					(thickness 0.15)
				)
			)
		)
		(property "Val" "100n"
			(at 0 0 0)
			(unlocked yes)
			(layer "F.Fab")
			(hide yes)
			(effects
				(font
					(size 1 1)
					(thickness 0.15)
				)
			)
		)
		(property "License" "Apache-2.0"
			(at 0 0 0)
			(unlocked yes)
			(layer "F.Fab")
			(hide yes)
			(effects
				(font
					(size 1 1)
					(thickness 0.15)
				)
			)
		)
		(property "Author" "Antmicro"
			(at 0 0 0)
			(unlocked yes)
			(layer "F.Fab")
			(hide yes)
			(effects
				(font
					(size 1 1)
					(thickness 0.15)
				)
			)
		)
		(property "Voltage" "50V"
			(at 0 0 0)
			(unlocked yes)
			(layer "F.Fab")
			(hide yes)
			(effects
				(font
					(size 1 1)
					(thickness 0.15)
				)
			)
		)
		(property "Dielectric" "X5R"
			(at 0 0 0)
			(unlocked yes)
			(layer "F.Fab")
			(hide yes)
			(effects
				(font
					(size 1 1)
					(thickness 0.15)
				)
			)
		)
		(sheetname "/SoM_IO/")
		(sheetfile "som_io.kicad_sch")
		(attr smd)
		(fp_poly
			(pts
				(xy -0.925 -0.47) (xy 0.925 -0.47) (xy 0.925 0.47) (xy -0.925 0.47)
			)
			(stroke
				(width 0.05)
				(type default)
			)
			(fill no)
			(layer "F.CrtYd")
		)
		(fp_line
			(start -0.494 -0.25)
			(end 0.504 -0.25)
			(stroke
				(width 0.15)
				(type solid)
			)
			(layer "F.Fab")
		)
		(fp_line
			(start -0.494 0.248)
			(end -0.494 -0.25)
			(stroke
				(width 0.15)
				(type solid)
			)
			(layer "F.Fab")
		)
		(fp_line
			(start 0.504 -0.25)
			(end 0.504 0.248)
			(stroke
				(width 0.15)
				(type solid)
			)
			(layer "F.Fab")
		)
		(fp_line
			(start 0.504 0.248)
			(end -0.494 0.248)
			(stroke
				(width 0.15)
				(type solid)
			)
			(layer "F.Fab")
		)
		(fp_text user "Author: Antmicro"
			(at -0.939 3.399 0)
			(layer "F.Fab")
			(effects
				(font
					(size 0.7 0.7)
					(thickness 0.15)
				)
				(justify left bottom)
			)
		)
		(fp_text user "License: Apache-2.0"
			(at -0.939 5.799 0)
			(layer "F.Fab")
			(effects
				(font
					(size 0.7 0.7)
					(thickness 0.15)
				)
				(justify left bottom)
			)
		)
		(fp_text user "${REFERENCE}"
			(at -0.939 4.599 0)
			(layer "F.Fab")
			(effects
				(font
					(size 0.7 0.7)
					(thickness 0.15)
				)
				(justify left bottom)
			)
		)
		(pad "1" smd roundrect
			(at -0.48 0)
			(size 0.59 0.64)
			(layers "F.Cu" "F.Mask" "F.Paste")
			(roundrect_rratio 0.25)
			(net 1 "GND")
			(pintype "passive")
		)
		(pad "2" smd roundrect
			(at 0.48 0)
			(size 0.59 0.64)
			(layers "F.Cu" "F.Mask" "F.Paste")
			(roundrect_rratio 0.25)
			(net 2 "+3V3")
			(pintype "passive")
		)
	)
	(footprint "antmicro-footprints:TP_SMD_0.75mm"
		(layer "F.Cu")
		(at 208.3 62 90)
		(property "Reference" "TP116"
			(at -0.4 -3.8 180)
			(layer "F.SilkS")
			(effects
				(font
					(size 0.7 0.7)
					(thickness 0.15)
				)
				(justify left bottom)
			)
		)
		(property "Value" "TP_0.75mm_SMD"
			(at 0 1.2 90)
			(layer "F.Fab")
			(effects
				(font
					(size 0.7 0.7)
					(thickness 0.15)
				)
				(justify left bottom)
			)
		)
		(property "Description" "SMT test point"
			(at 0 0 90)
			(layer "F.Fab")
			(hide yes)
			(effects
				(font
					(size 1.27 1.27)
					(thickness 0.15)
				)
			)
		)
		(property "MPN" ""
			(at 0 0 90)
			(unlocked yes)
			(layer "F.Fab")
			(hide yes)
			(effects
				(font
					(size 1 1)
					(thickness 0.15)
				)
			)
		)
		(property "Manufacturer" ""
			(at 0 0 90)
			(unlocked yes)
			(layer "F.Fab")
			(hide yes)
			(effects
				(font
					(size 1 1)
					(thickness 0.15)
				)
			)
		)
		(property "Author" "Antmicro"
			(at 0 0 90)
			(unlocked yes)
			(layer "F.Fab")
			(hide yes)
			(effects
				(font
					(size 1 1)
					(thickness 0.15)
				)
			)
		)
		(property "License" "Apache-2.0"
			(at 0 0 90)
			(unlocked yes)
			(layer "F.Fab")
			(hide yes)
			(effects
				(font
					(size 1 1)
					(thickness 0.15)
				)
			)
		)
		(sheetname "/Power/")
		(sheetfile "power.kicad_sch")
		(attr exclude_from_pos_files exclude_from_bom)
		(fp_circle
			(center 0 0)
			(end 0.475 0)
			(stroke
				(width 0.05)
				(type default)
			)
			(fill no)
			(layer "F.CrtYd")
		)
		(fp_text user "License: Apache-2.0"
			(at -0.4 5.101 90)
			(layer "F.Fab")
			(effects
				(font
					(size 0.7 0.7)
					(thickness 0.15)
				)
				(justify left bottom)
			)
		)
		(fp_text user "Author: Antmicro"
			(at -0.4 3.901 90)
			(layer "F.Fab")
			(effects
				(font
					(size 0.7 0.7)
					(thickness 0.15)
				)
				(justify left bottom)
			)
		)
		(fp_text user "${REFERENCE}"
			(at -0.4 2.7 90)
			(layer "F.Fab")
			(effects
				(font
					(size 0.7 0.7)
					(thickness 0.15)
				)
				(justify left bottom)
			)
		)
		(pad "1" smd circle
			(at 0 0 90)
			(size 0.75 0.75)
			(layers "F.Cu" "F.Mask")
			(net 1383 "VCC_NO_OVP")
			(pinfunction "1")
			(pintype "passive")
		)
	)
)
